FILE_TYPE = CONNECTIVITY;
{Allegro Design Entry HDL 17.2-2016 S081 (4005846) 1/11/2022}
"PAGE_NUMBER" = 58;
0"NC";
1"GND_P1\g";
2"GND_P1\g";
3"GND_P1\g";
4"GND_P1\g";
5"GND_P1\g";
6"GND_P1\g";
7"GND_P1\g";
8"GND_P1\g";
9"GND_P1\g";
10"GND_P1\g";
11"GND_P1\g";
12"GND_P1\g";
13"GND_P1\g";
14"GND_P1\g";
15"GND_P1\g";
16"GND_P1\g";
17"85_5INCH_IN1_DP";
18"85_5INCH_IN4_DN";
19"85_5INCH_IN4_DP";
20"85_5INCH_BOT_DP";
21"85_5INCH_BOT_DN";
22"85_10INCH_BOT_DP";
23"85_10INCH_BOT_DN";
24"85_10INCH_IN4_DN";
25"85_10INCH_IN4_DP";
26"85_10INCH_IN1_DP";
27"85_10INCH_IN1_DN";
28"85_10INCH_TOP_DN";
29"85_10INCH_TOP_DP";
30"85_5INCH_IN1_DN";
31"85_5INCH_TOP_DP";
32"85_5INCH_TOP_DN";
%"UNIVERSAL_GND"
"1","(-425,2275)","0","logical_power","I18";
;
HDL_POWER"GND_P1"
CDS_LIB"logical_power";
"A"13;
%"UNIVERSAL_GND"
"1","(-8075,3275)","0","logical_power","I2";
;
HDL_POWER"GND_P1"
CDS_LIB"logical_power";
"A"9;
%"UNIVERSAL_GND"
"1","(-3900,2275)","0","logical_power","I25";
;
HDL_POWER"GND_P1"
CDS_LIB"logical_power";
"A"15;
%"UNIVERSAL_GND"
"1","(-225,-800)","0","logical_power","I35";
;
HDL_POWER"GND_P1"
CDS_LIB"logical_power";
"A"14;
%"UNIVERSAL_GND"
"1","(-3700,-800)","0","logical_power","I39";
;
HDL_POWER"GND_P1"
CDS_LIB"logical_power";
"A"3;
%"UNIVERSAL_GND"
"1","(-4525,200)","0","logical_power","I40";
;
HDL_POWER"GND_P1"
CDS_LIB"logical_power";
"A"12;
%"UNIVERSAL_GND"
"1","(-8000,200)","0","logical_power","I46";
;
HDL_POWER"GND_P1"
CDS_LIB"logical_power";
"A"5;
%"UNIVERSAL_GND"
"1","(-7975,-725)","0","logical_power","I47";
;
HDL_POWER"GND_P1"
CDS_LIB"logical_power";
"A"10;
%"UNIVERSAL_GND"
"1","(-4500,-725)","0","logical_power","I48";
;
HDL_POWER"GND_P1"
CDS_LIB"logical_power";
"A"11;
%"UNIVERSAL_GND"
"1","(-3700,150)","0","logical_power","I49";
;
HDL_POWER"GND_P1"
CDS_LIB"logical_power";
"A"4;
%"UNIVERSAL_GND"
"1","(-4600,3275)","0","logical_power","I5";
;
HDL_POWER"GND_P1"
CDS_LIB"logical_power";
"A"2;
%"UNIVERSAL_GND"
"1","(-225,150)","0","logical_power","I50";
;
HDL_POWER"GND_P1"
CDS_LIB"logical_power";
"A"1;
%"UNIVERSAL_GND"
"1","(-3900,3225)","0","logical_power","I51";
;
HDL_POWER"GND_P1"
CDS_LIB"logical_power";
"A"7;
%"UNIVERSAL_GND"
"1","(-425,3225)","0","logical_power","I52";
;
HDL_POWER"GND_P1"
CDS_LIB"logical_power";
"A"16;
%"UNIVERSAL_GND"
"1","(-4600,2400)","0","logical_power","I53";
;
HDL_POWER"GND_P1"
CDS_LIB"logical_power";
"A"6;
%"UNIVERSAL_GND"
"1","(-8075,2400)","0","logical_power","I54";
;
HDL_POWER"GND_P1"
CDS_LIB"logical_power";
"A"8;
%"PICOPROBE_BXA"
"1","(-7675,3625)","0","pure_quanta","I55";
;
MATERIAL"EMPTY"
PART_NUMBER"TP33"
PART_TYPE"SMLF"
VALUE"DELTA-L 4.0"
CDS_LMAN_SYM_OUTLINE"-150,100,150,-100"
CDS_LIB"pure_quanta"
NEEDS_NO_SIZE"TRUE"
LOCATION"J9"
$SEC"1"
CDS_SEC"1";
"1_P"
$PN"1"32;
"3_G"
$PN"3"9;
"2_N"
$PN"2"31;
%"PICOPROBE_BXA"
"1","(-7675,2750)","0","pure_quanta","I57";
;
PART_NUMBER"TP33"
MATERIAL"EMPTY"
VALUE"DELTA-L 4.0"
PART_TYPE"SMLF"
CDS_LIB"pure_quanta"
CDS_LMAN_SYM_OUTLINE"-150,100,150,-100"
NEEDS_NO_SIZE"TRUE"
LOCATION"J11"
$SEC"1"
CDS_SEC"1";
"1_P"
$PN"1"30;
"3_G"
$PN"3"8;
"2_N"
$PN"2"17;
%"PICOPROBE_BXA"
"1","(-3500,3575)","0","pure_quanta","I58";
;
VALUE"DELTA-L 4.0"
PART_TYPE"SMLF"
PART_NUMBER"TP33"
MATERIAL"EMPTY"
NEEDS_NO_SIZE"TRUE"
CDS_LMAN_SYM_OUTLINE"-150,100,150,-100"
CDS_LIB"pure_quanta"
LOCATION"J16"
$SEC"1"
CDS_SEC"1";
"1_P"
$PN"1"18;
"3_G"
$PN"3"7;
"2_N"
$PN"2"19;
%"PICOPROBE_BXA"
"1","(-3500,2650)","0","pure_quanta","I59";
;
VALUE"DELTA-L 4.0"
PART_TYPE"SMLF"
PART_NUMBER"TP33"
MATERIAL"EMPTY"
NEEDS_NO_SIZE"TRUE"
CDS_LMAN_SYM_OUTLINE"-150,100,150,-100"
CDS_LIB"pure_quanta"
LOCATION"J17"
$SEC"1"
CDS_SEC"1";
"1_P"
$PN"1"21;
"3_G"
$PN"3"15;
"2_N"
$PN"2"20;
%"PICOPROBE_BXA"
"1","(-7600,550)","0","pure_quanta","I60";
;
VALUE"DELTA-L 4.0"
PART_TYPE"SMLF"
PART_NUMBER"TP33"
MATERIAL"EMPTY"
NEEDS_NO_SIZE"TRUE"
CDS_LMAN_SYM_OUTLINE"-150,100,150,-100"
CDS_LIB"pure_quanta"
LOCATION"J25"
$SEC"1"
CDS_SEC"1";
"1_P"
$PN"1"28;
"3_G"
$PN"3"5;
"2_N"
$PN"2"29;
%"PICOPROBE_BXA"
"1","(-7575,-375)","0","pure_quanta","I61";
;
PART_NUMBER"TP33"
MATERIAL"EMPTY"
PART_TYPE"SMLF"
VALUE"DELTA-L 4.0"
NEEDS_NO_SIZE"TRUE"
CDS_LMAN_SYM_OUTLINE"-150,100,150,-100"
CDS_LIB"pure_quanta"
LOCATION"J28"
$SEC"1"
CDS_SEC"1";
"1_P"
$PN"1"27;
"3_G"
$PN"3"10;
"2_N"
$PN"2"26;
%"PICOPROBE_BXA"
"1","(-3300,500)","0","pure_quanta","I62";
;
PART_NUMBER"TP33"
PART_TYPE"SMLF"
VALUE"DELTA-L 4.0"
MATERIAL"EMPTY"
NEEDS_NO_SIZE"TRUE"
CDS_LMAN_SYM_OUTLINE"-150,100,150,-100"
CDS_LIB"pure_quanta"
LOCATION"J26"
$SEC"1"
CDS_SEC"1";
"1_P"
$PN"1"24;
"3_G"
$PN"3"4;
"2_N"
$PN"2"25;
%"PICOPROBE_BXA"
"1","(-3300,-425)","0","pure_quanta","I63";
;
PART_TYPE"SMLF"
PART_NUMBER"TP33"
MATERIAL"EMPTY"
VALUE"DELTA-L 4.0"
NEEDS_NO_SIZE"TRUE"
CDS_LMAN_SYM_OUTLINE"-150,100,150,-100"
CDS_LIB"pure_quanta"
LOCATION"J27"
$SEC"1"
CDS_SEC"1";
"1_P"
$PN"1"23;
"3_G"
$PN"3"3;
"2_N"
$PN"2"22;
%"PICOPROBE_BXA"
"1","(-5000,3675)","4","pure_quanta","I64";
;
MATERIAL"EMPTY"
PART_NUMBER"TP33"
VALUE"DELTA-L 4.0"
PART_TYPE"SMLF"
CDS_LMAN_SYM_OUTLINE"-150,100,150,-100"
CDS_LIB"pure_quanta"
NEEDS_NO_SIZE"TRUE"
LOCATION"J12"
$SEC"1"
CDS_SEC"1";
"1_P"
$PN"1"31;
"3_G"
$PN"3"2;
"2_N"
$PN"2"32;
%"PICOPROBE_BXA"
"1","(-5000,2800)","4","pure_quanta","I65";
;
MATERIAL"EMPTY"
PART_NUMBER"TP33"
VALUE"DELTA-L 4.0"
PART_TYPE"SMLF"
NEEDS_NO_SIZE"TRUE"
CDS_LMAN_SYM_OUTLINE"-150,100,150,-100"
CDS_LIB"pure_quanta"
LOCATION"J29"
$SEC"1"
CDS_SEC"1";
"1_P"
$PN"1"17;
"3_G"
$PN"3"6;
"2_N"
$PN"2"30;
%"PICOPROBE_BXA"
"1","(-4925,600)","4","pure_quanta","I66";
;
PART_TYPE"SMLF"
VALUE"DELTA-L 4.0"
PART_NUMBER"TP33"
MATERIAL"EMPTY"
NEEDS_NO_SIZE"TRUE"
CDS_LMAN_SYM_OUTLINE"-150,100,150,-100"
CDS_LIB"pure_quanta"
LOCATION"J22"
$SEC"1"
CDS_SEC"1";
"1_P"
$PN"1"29;
"3_G"
$PN"3"12;
"2_N"
$PN"2"28;
%"PICOPROBE_BXA"
"1","(-4900,-325)","4","pure_quanta","I67";
;
MATERIAL"EMPTY"
PART_NUMBER"TP33"
VALUE"DELTA-L 4.0"
PART_TYPE"SMLF"
CDS_LIB"pure_quanta"
CDS_LMAN_SYM_OUTLINE"-150,100,150,-100"
NEEDS_NO_SIZE"TRUE"
LOCATION"J30"
$SEC"1"
CDS_SEC"1";
"1_P"
$PN"1"26;
"3_G"
$PN"3"11;
"2_N"
$PN"2"27;
%"PICOPROBE_BXA"
"1","(-625,-375)","4","pure_quanta","I68";
;
PART_TYPE"SMLF"
VALUE"DELTA-L 4.0"
PART_NUMBER"TP33"
MATERIAL"EMPTY"
NEEDS_NO_SIZE"TRUE"
CDS_LMAN_SYM_OUTLINE"-150,100,150,-100"
CDS_LIB"pure_quanta"
LOCATION"J24"
$SEC"1"
CDS_SEC"1";
"1_P"
$PN"1"22;
"3_G"
$PN"3"14;
"2_N"
$PN"2"23;
%"PICOPROBE_BXA"
"1","(-625,550)","4","pure_quanta","I69";
;
MATERIAL"EMPTY"
PART_NUMBER"TP33"
VALUE"DELTA-L 4.0"
PART_TYPE"SMLF"
NEEDS_NO_SIZE"TRUE"
CDS_LMAN_SYM_OUTLINE"-150,100,150,-100"
CDS_LIB"pure_quanta"
LOCATION"J23"
$SEC"1"
CDS_SEC"1";
"1_P"
$PN"1"25;
"3_G"
$PN"3"1;
"2_N"
$PN"2"24;
%"PICOPROBE_BXA"
"1","(-825,2700)","4","pure_quanta","I70";
;
MATERIAL"EMPTY"
PART_NUMBER"TP33"
VALUE"DELTA-L 4.0"
PART_TYPE"SMLF"
NEEDS_NO_SIZE"TRUE"
CDS_LMAN_SYM_OUTLINE"-150,100,150,-100"
CDS_LIB"pure_quanta"
LOCATION"J20"
$SEC"1"
CDS_SEC"1";
"1_P"
$PN"1"20;
"3_G"
$PN"3"13;
"2_N"
$PN"2"21;
%"PICOPROBE_BXA"
"1","(-825,3625)","4","pure_quanta","I71";
;
PART_NUMBER"TP33"
VALUE"DELTA-L 4.0"
PART_TYPE"SMLF"
MATERIAL"EMPTY"
NEEDS_NO_SIZE"TRUE"
CDS_LMAN_SYM_OUTLINE"-150,100,150,-100"
CDS_LIB"pure_quanta"
LOCATION"J19"
$SEC"1"
CDS_SEC"1";
"1_P"
$PN"1"19;
"3_G"
$PN"3"16;
"2_N"
$PN"2"18;
END.
